(kicad_pcb
	(version 20260206)
	(generator "pcbnew")
	(generator_version "10.0")
	(general
		(thickness 1.6)
		(legacy_teardrops no)
	)
	(paper "A4")
	(title_block
		(title "03242023_DA0F0TMBIJ0_F0T_Motherboard_J_brd_V01_OCP.brd")
		(comment 1 "Grand Teton / footprints 491-496 of 6105")
	)
	(layers
		(0 "F.Cu" signal "TOP")
		(4 "In1.Cu" signal "GND")
		(6 "In2.Cu" signal "IN1")
		(8 "In3.Cu" signal "GND1")
		(10 "In4.Cu" signal "IN2")
		(12 "In5.Cu" signal "GND2")
		(14 "In6.Cu" signal "IN3")
		(16 "In7.Cu" signal "GND3")
		(18 "In8.Cu" signal "VCC")
		(20 "In9.Cu" signal "VCC1")
		(22 "In10.Cu" signal "GND4")
		(24 "In11.Cu" signal "IN4")
		(26 "In12.Cu" signal "GND5")
		(28 "In13.Cu" signal "IN5")
		(30 "In14.Cu" signal "GND6")
		(32 "In15.Cu" signal "IN6")
		(34 "In16.Cu" signal "GND7")
		(2 "B.Cu" signal "BOTTOM")
		(9 "F.Adhes" user "F.Adhesive")
		(11 "B.Adhes" user "B.Adhesive")
		(13 "F.Paste" user "Package Geometry/Pastemask Top")
		(15 "B.Paste" user "Package Geometry/Pastemask Bottom")
		(5 "F.SilkS" user "Ref Des/Silkscreen Top")
		(7 "B.SilkS" user "Ref Des/Silkscreen Bottom")
		(1 "F.Mask" user "Board Geometry/Soldermask Top")
		(3 "B.Mask" user "Board Geometry/Soldermask Bottom")
		(17 "Dwgs.User" user "User.Drawings")
		(19 "Cmts.User" user "User.Comments")
		(21 "Eco1.User" user "User.Eco1")
		(23 "Eco2.User" user "User.Eco2")
		(25 "Edge.Cuts" user "Board Geometry/Outline")
		(27 "Margin" user)
		(31 "F.CrtYd" user "Package Geometry/Place Bound Top")
		(29 "B.CrtYd" user "Package Geometry/Place Bound Bottom")
		(35 "F.Fab" user "Ref Des/Assembly Top")
		(33 "B.Fab" user "Ref Des/Assembly Bottom")
	)
	(footprint ""
		(layer "F.Cu")
		(at 314.03544 -63.076328 180)
		(property "Reference" "R4565"
			(at 0 0 180)
			(layer "F.SilkS")
			(hide yes)
			(effects
				(font
					(size 1.27 1.27)
				)
			)
		)
		(property "Value" ""
			(at 0 0 180)
			(layer "F.Fab")
			(effects
				(font
					(size 1.27 1.27)
				)
			)
		)
		(duplicate_pad_numbers_are_jumpers no)
		(fp_line
			(start 0.7874 0.4064)
			(end -0.7874 0.4064)
			(stroke
				(width 0.1524)
				(type default)
			)
			(layer "F.SilkS")
		)
		(fp_line
			(start 0.7874 -0.4064)
			(end 0.7874 0.4064)
			(stroke
				(width 0.1524)
				(type default)
			)
			(layer "F.SilkS")
		)
		(fp_line
			(start -0.7874 0.4064)
			(end -0.7874 -0.4064)
			(stroke
				(width 0.1524)
				(type default)
			)
			(layer "F.SilkS")
		)
		(fp_line
			(start -0.7874 -0.4064)
			(end 0.7874 -0.4064)
			(stroke
				(width 0.1524)
				(type default)
			)
			(layer "F.SilkS")
		)
		(fp_line
			(start 0.67945 0.3048)
			(end 0.120396 0.3048)
			(stroke
				(width 0.1)
				(type default)
			)
			(layer "F.Fab")
		)
		(fp_line
			(start 0.67945 -0.3048)
			(end 0.67945 0.3048)
			(stroke
				(width 0.1)
				(type default)
			)
			(layer "F.Fab")
		)
		(fp_line
			(start 0.12065 -0.2794)
			(end 0.12065 -0.3048)
			(stroke
				(width 0.1)
				(type default)
			)
			(layer "F.Fab")
		)
		(fp_line
			(start 0.12065 -0.3048)
			(end 0.67945 -0.3048)
			(stroke
				(width 0.1)
				(type default)
			)
			(layer "F.Fab")
		)
		(fp_line
			(start 0.120396 0.3048)
			(end 0.120396 0.2794)
			(stroke
				(width 0.1)
				(type default)
			)
			(layer "F.Fab")
		)
		(fp_line
			(start 0.120396 0.2794)
			(end -0.12065 0.2794)
			(stroke
				(width 0.1)
				(type default)
			)
			(layer "F.Fab")
		)
		(fp_line
			(start -0.12065 0.3048)
			(end -0.67945 0.3048)
			(stroke
				(width 0.1)
				(type default)
			)
			(layer "F.Fab")
		)
		(fp_line
			(start -0.12065 0.2794)
			(end -0.12065 0.3048)
			(stroke
				(width 0.1)
				(type default)
			)
			(layer "F.Fab")
		)
		(fp_line
			(start -0.12065 -0.2794)
			(end 0.12065 -0.2794)
			(stroke
				(width 0.1)
				(type default)
			)
			(layer "F.Fab")
		)
		(fp_line
			(start -0.12065 -0.305054)
			(end -0.12065 -0.2794)
			(stroke
				(width 0.1)
				(type default)
			)
			(layer "F.Fab")
		)
		(fp_line
			(start -0.67945 0.3048)
			(end -0.67945 -0.305054)
			(stroke
				(width 0.1)
				(type default)
			)
			(layer "F.Fab")
		)
		(fp_line
			(start -0.67945 -0.305054)
			(end -0.12065 -0.305054)
			(stroke
				(width 0.1)
				(type default)
			)
			(layer "F.Fab")
		)
		(pad "1" smd circle
			(at -0.40005 0 180)
			(size 0 0)
			(layers "F.Cu" "F.Mask" "F.Paste")
			(net "PD_GPP_I_13")
		)
		(pad "2" smd circle
			(at 0.40005 0 180)
			(size 0 0)
			(layers "F.Cu" "F.Mask" "F.Paste")
			(net "GND")
		)
	)
	(footprint ""
		(layer "F.Cu")
		(at 68.2117 -36.294568)
		(property "Reference" "R4092"
			(at 0 0 0)
			(layer "F.SilkS")
			(hide yes)
			(effects
				(font
					(size 1.27 1.27)
				)
			)
		)
		(property "Value" ""
			(at 0 0 0)
			(layer "F.Fab")
			(effects
				(font
					(size 1.27 1.27)
				)
			)
		)
		(duplicate_pad_numbers_are_jumpers no)
		(fp_line
			(start -0.7874 -0.4064)
			(end 0.7874 -0.4064)
			(stroke
				(width 0.1524)
				(type default)
			)
			(layer "F.SilkS")
		)
		(fp_line
			(start -0.7874 0.4064)
			(end -0.7874 -0.4064)
			(stroke
				(width 0.1524)
				(type default)
			)
			(layer "F.SilkS")
		)
		(fp_line
			(start 0.7874 -0.4064)
			(end 0.7874 0.4064)
			(stroke
				(width 0.1524)
				(type default)
			)
			(layer "F.SilkS")
		)
		(fp_line
			(start 0.7874 0.4064)
			(end -0.7874 0.4064)
			(stroke
				(width 0.1524)
				(type default)
			)
			(layer "F.SilkS")
		)
		(fp_line
			(start -0.67945 -0.305054)
			(end -0.12065 -0.305054)
			(stroke
				(width 0.1)
				(type default)
			)
			(layer "F.Fab")
		)
		(fp_line
			(start -0.67945 0.3048)
			(end -0.67945 -0.305054)
			(stroke
				(width 0.1)
				(type default)
			)
			(layer "F.Fab")
		)
		(fp_line
			(start -0.12065 -0.305054)
			(end -0.12065 -0.2794)
			(stroke
				(width 0.1)
				(type default)
			)
			(layer "F.Fab")
		)
		(fp_line
			(start -0.12065 -0.2794)
			(end 0.12065 -0.2794)
			(stroke
				(width 0.1)
				(type default)
			)
			(layer "F.Fab")
		)
		(fp_line
			(start -0.12065 0.2794)
			(end -0.12065 0.3048)
			(stroke
				(width 0.1)
				(type default)
			)
			(layer "F.Fab")
		)
		(fp_line
			(start -0.12065 0.3048)
			(end -0.67945 0.3048)
			(stroke
				(width 0.1)
				(type default)
			)
			(layer "F.Fab")
		)
		(fp_line
			(start 0.120396 0.2794)
			(end -0.12065 0.2794)
			(stroke
				(width 0.1)
				(type default)
			)
			(layer "F.Fab")
		)
		(fp_line
			(start 0.120396 0.3048)
			(end 0.120396 0.2794)
			(stroke
				(width 0.1)
				(type default)
			)
			(layer "F.Fab")
		)
		(fp_line
			(start 0.12065 -0.3048)
			(end 0.67945 -0.3048)
			(stroke
				(width 0.1)
				(type default)
			)
			(layer "F.Fab")
		)
		(fp_line
			(start 0.12065 -0.2794)
			(end 0.12065 -0.3048)
			(stroke
				(width 0.1)
				(type default)
			)
			(layer "F.Fab")
		)
		(fp_line
			(start 0.67945 -0.3048)
			(end 0.67945 0.3048)
			(stroke
				(width 0.1)
				(type default)
			)
			(layer "F.Fab")
		)
		(fp_line
			(start 0.67945 0.3048)
			(end 0.120396 0.3048)
			(stroke
				(width 0.1)
				(type default)
			)
			(layer "F.Fab")
		)
		(pad "1" smd circle
			(at -0.40005 0)
			(size 0 0)
			(layers "F.Cu" "F.Mask" "F.Paste")
			(net "P3V3_AUX")
		)
		(pad "2" smd circle
			(at 0.40005 0)
			(size 0 0)
			(layers "F.Cu" "F.Mask" "F.Paste")
			(net "OCP_V3_2_P3V3_ADC_ALERT_R")
		)
	)
	(footprint ""
		(layer "F.Cu")
		(at 73.6092 -53.546248 180)
		(property "Reference" "PC2142"
			(at 0 0 180)
			(layer "F.SilkS")
			(hide yes)
			(effects
				(font
					(size 1.27 1.27)
				)
			)
		)
		(property "Value" ""
			(at 0 0 180)
			(layer "F.Fab")
			(effects
				(font
					(size 1.27 1.27)
				)
			)
		)
		(duplicate_pad_numbers_are_jumpers no)
		(fp_line
			(start 1.524 0.762)
			(end -1.524 0.762)
			(stroke
				(width 0.1524)
				(type default)
			)
			(layer "F.SilkS")
		)
		(fp_line
			(start 1.524 -0.762)
			(end 1.524 0.762)
			(stroke
				(width 0.1524)
				(type default)
			)
			(layer "F.SilkS")
		)
		(fp_line
			(start -1.524 0.762)
			(end -1.524 -0.762)
			(stroke
				(width 0.1524)
				(type default)
			)
			(layer "F.SilkS")
		)
		(fp_line
			(start -1.524 -0.762)
			(end 1.524 -0.762)
			(stroke
				(width 0.1524)
				(type default)
			)
			(layer "F.SilkS")
		)
		(fp_line
			(start 1.1049 0.724916)
			(end 1.1049 -0.724916)
			(stroke
				(width 0.1)
				(type default)
			)
			(layer "F.Fab")
		)
		(fp_line
			(start 1.1049 -0.724916)
			(end -1.1049 -0.724916)
			(stroke
				(width 0.1)
				(type default)
			)
			(layer "F.Fab")
		)
		(fp_line
			(start -1.1049 0.724916)
			(end 1.1049 0.724916)
			(stroke
				(width 0.1)
				(type default)
			)
			(layer "F.Fab")
		)
		(fp_line
			(start -1.1049 -0.724916)
			(end -1.1049 0.724916)
			(stroke
				(width 0.1)
				(type default)
			)
			(layer "F.Fab")
		)
		(pad "1" smd rect
			(at -0.889 0)
			(size 1.016 1.27)
			(layers "F.Cu" "F.Mask" "F.Paste")
			(net "P3V3_OCP_V3_2_R")
		)
		(pad "2" smd rect
			(at 0.889 0)
			(size 1.016 1.27)
			(layers "F.Cu" "F.Mask" "F.Paste")
			(net "GND")
		)
	)
	(footprint ""
		(layer "F.Cu")
		(at 294.39108 -53.68798 180)
		(property "Reference" "R4072"
			(at 0 0 180)
			(layer "F.SilkS")
			(hide yes)
			(effects
				(font
					(size 1.27 1.27)
				)
			)
		)
		(property "Value" ""
			(at 0 0 180)
			(layer "F.Fab")
			(effects
				(font
					(size 1.27 1.27)
				)
			)
		)
		(duplicate_pad_numbers_are_jumpers no)
		(fp_line
			(start 0.7874 0.4064)
			(end -0.7874 0.4064)
			(stroke
				(width 0.1524)
				(type default)
			)
			(layer "F.SilkS")
		)
		(fp_line
			(start 0.7874 -0.4064)
			(end 0.7874 0.4064)
			(stroke
				(width 0.1524)
				(type default)
			)
			(layer "F.SilkS")
		)
		(fp_line
			(start -0.7874 0.4064)
			(end -0.7874 -0.4064)
			(stroke
				(width 0.1524)
				(type default)
			)
			(layer "F.SilkS")
		)
		(fp_line
			(start -0.7874 -0.4064)
			(end 0.7874 -0.4064)
			(stroke
				(width 0.1524)
				(type default)
			)
			(layer "F.SilkS")
		)
		(fp_line
			(start 0.67945 0.3048)
			(end 0.120396 0.3048)
			(stroke
				(width 0.1)
				(type default)
			)
			(layer "F.Fab")
		)
		(fp_line
			(start 0.67945 -0.3048)
			(end 0.67945 0.3048)
			(stroke
				(width 0.1)
				(type default)
			)
			(layer "F.Fab")
		)
		(fp_line
			(start 0.12065 -0.2794)
			(end 0.12065 -0.3048)
			(stroke
				(width 0.1)
				(type default)
			)
			(layer "F.Fab")
		)
		(fp_line
			(start 0.12065 -0.3048)
			(end 0.67945 -0.3048)
			(stroke
				(width 0.1)
				(type default)
			)
			(layer "F.Fab")
		)
		(fp_line
			(start 0.120396 0.3048)
			(end 0.120396 0.2794)
			(stroke
				(width 0.1)
				(type default)
			)
			(layer "F.Fab")
		)
		(fp_line
			(start 0.120396 0.2794)
			(end -0.12065 0.2794)
			(stroke
				(width 0.1)
				(type default)
			)
			(layer "F.Fab")
		)
		(fp_line
			(start -0.12065 0.3048)
			(end -0.67945 0.3048)
			(stroke
				(width 0.1)
				(type default)
			)
			(layer "F.Fab")
		)
		(fp_line
			(start -0.12065 0.2794)
			(end -0.12065 0.3048)
			(stroke
				(width 0.1)
				(type default)
			)
			(layer "F.Fab")
		)
		(fp_line
			(start -0.12065 -0.2794)
			(end 0.12065 -0.2794)
			(stroke
				(width 0.1)
				(type default)
			)
			(layer "F.Fab")
		)
		(fp_line
			(start -0.12065 -0.305054)
			(end -0.12065 -0.2794)
			(stroke
				(width 0.1)
				(type default)
			)
			(layer "F.Fab")
		)
		(fp_line
			(start -0.67945 0.3048)
			(end -0.67945 -0.305054)
			(stroke
				(width 0.1)
				(type default)
			)
			(layer "F.Fab")
		)
		(fp_line
			(start -0.67945 -0.305054)
			(end -0.12065 -0.305054)
			(stroke
				(width 0.1)
				(type default)
			)
			(layer "F.Fab")
		)
		(pad "1" smd circle
			(at -0.40005 0 180)
			(size 0 0)
			(layers "F.Cu" "F.Mask" "F.Paste")
			(net "P12V_AUX")
		)
		(pad "2" smd circle
			(at 0.40005 0 180)
			(size 0 0)
			(layers "F.Cu" "F.Mask" "F.Paste")
			(net "P3V3_E1S_0_EN_G")
		)
	)
	(footprint ""
		(layer "F.Cu")
		(at 46.087792 -393.315444)
		(property "Reference" "R4647"
			(at 0 0 0)
			(layer "F.SilkS")
			(hide yes)
			(effects
				(font
					(size 1.27 1.27)
				)
			)
		)
		(property "Value" ""
			(at 0 0 0)
			(layer "F.Fab")
			(effects
				(font
					(size 1.27 1.27)
				)
			)
		)
		(duplicate_pad_numbers_are_jumpers no)
		(fp_line
			(start -0.7874 -0.4064)
			(end 0.7874 -0.4064)
			(stroke
				(width 0.1524)
				(type default)
			)
			(layer "F.SilkS")
		)
		(fp_line
			(start -0.7874 0.4064)
			(end -0.7874 -0.4064)
			(stroke
				(width 0.1524)
				(type default)
			)
			(layer "F.SilkS")
		)
		(fp_line
			(start 0.7874 -0.4064)
			(end 0.7874 0.4064)
			(stroke
				(width 0.1524)
				(type default)
			)
			(layer "F.SilkS")
		)
		(fp_line
			(start 0.7874 0.4064)
			(end -0.7874 0.4064)
			(stroke
				(width 0.1524)
				(type default)
			)
			(layer "F.SilkS")
		)
		(fp_line
			(start -0.67945 -0.305054)
			(end -0.12065 -0.305054)
			(stroke
				(width 0.1)
				(type default)
			)
			(layer "F.Fab")
		)
		(fp_line
			(start -0.67945 0.3048)
			(end -0.67945 -0.305054)
			(stroke
				(width 0.1)
				(type default)
			)
			(layer "F.Fab")
		)
		(fp_line
			(start -0.12065 -0.305054)
			(end -0.12065 -0.2794)
			(stroke
				(width 0.1)
				(type default)
			)
			(layer "F.Fab")
		)
		(fp_line
			(start -0.12065 -0.2794)
			(end 0.12065 -0.2794)
			(stroke
				(width 0.1)
				(type default)
			)
			(layer "F.Fab")
		)
		(fp_line
			(start -0.12065 0.2794)
			(end -0.12065 0.3048)
			(stroke
				(width 0.1)
				(type default)
			)
			(layer "F.Fab")
		)
		(fp_line
			(start -0.12065 0.3048)
			(end -0.67945 0.3048)
			(stroke
				(width 0.1)
				(type default)
			)
			(layer "F.Fab")
		)
		(fp_line
			(start 0.120396 0.2794)
			(end -0.12065 0.2794)
			(stroke
				(width 0.1)
				(type default)
			)
			(layer "F.Fab")
		)
		(fp_line
			(start 0.120396 0.3048)
			(end 0.120396 0.2794)
			(stroke
				(width 0.1)
				(type default)
			)
			(layer "F.Fab")
		)
		(fp_line
			(start 0.12065 -0.3048)
			(end 0.67945 -0.3048)
			(stroke
				(width 0.1)
				(type default)
			)
			(layer "F.Fab")
		)
		(fp_line
			(start 0.12065 -0.2794)
			(end 0.12065 -0.3048)
			(stroke
				(width 0.1)
				(type default)
			)
			(layer "F.Fab")
		)
		(fp_line
			(start 0.67945 -0.3048)
			(end 0.67945 0.3048)
			(stroke
				(width 0.1)
				(type default)
			)
			(layer "F.Fab")
		)
		(fp_line
			(start 0.67945 0.3048)
			(end 0.120396 0.3048)
			(stroke
				(width 0.1)
				(type default)
			)
			(layer "F.Fab")
		)
		(pad "1" smd circle
			(at -0.40005 0)
			(size 0 0)
			(layers "F.Cu" "F.Mask" "F.Paste")
			(net "FM_P2E_BUF2_VODA_DB")
		)
		(pad "2" smd circle
			(at 0.40005 0)
			(size 0 0)
			(layers "F.Cu" "F.Mask" "F.Paste")
			(net "GND")
		)
	)
	(footprint ""
		(layer "F.Cu")
		(at 9.58088 -54.955948)
		(property "Reference" "R3061"
			(at 0 0 0)
			(layer "F.SilkS")
			(hide yes)
			(effects
				(font
					(size 1.27 1.27)
				)
			)
		)
		(property "Value" ""
			(at 0 0 0)
			(layer "F.Fab")
			(effects
				(font
					(size 1.27 1.27)
				)
			)
		)
		(duplicate_pad_numbers_are_jumpers no)
		(fp_line
			(start -0.7874 -0.4064)
			(end 0.7874 -0.4064)
			(stroke
				(width 0.1524)
				(type default)
			)
			(layer "F.SilkS")
		)
		(fp_line
			(start -0.7874 0.4064)
			(end -0.7874 -0.4064)
			(stroke
				(width 0.1524)
				(type default)
			)
			(layer "F.SilkS")
		)
		(fp_line
			(start 0.7874 -0.4064)
			(end 0.7874 0.4064)
			(stroke
				(width 0.1524)
				(type default)
			)
			(layer "F.SilkS")
		)
		(fp_line
			(start 0.7874 0.4064)
			(end -0.7874 0.4064)
			(stroke
				(width 0.1524)
				(type default)
			)
			(layer "F.SilkS")
		)
		(fp_line
			(start -0.67945 -0.305054)
			(end -0.12065 -0.305054)
			(stroke
				(width 0.1)
				(type default)
			)
			(layer "F.Fab")
		)
		(fp_line
			(start -0.67945 0.3048)
			(end -0.67945 -0.305054)
			(stroke
				(width 0.1)
				(type default)
			)
			(layer "F.Fab")
		)
		(fp_line
			(start -0.12065 -0.305054)
			(end -0.12065 -0.2794)
			(stroke
				(width 0.1)
				(type default)
			)
			(layer "F.Fab")
		)
		(fp_line
			(start -0.12065 -0.2794)
			(end 0.12065 -0.2794)
			(stroke
				(width 0.1)
				(type default)
			)
			(layer "F.Fab")
		)
		(fp_line
			(start -0.12065 0.2794)
			(end -0.12065 0.3048)
			(stroke
				(width 0.1)
				(type default)
			)
			(layer "F.Fab")
		)
		(fp_line
			(start -0.12065 0.3048)
			(end -0.67945 0.3048)
			(stroke
				(width 0.1)
				(type default)
			)
			(layer "F.Fab")
		)
		(fp_line
			(start 0.120396 0.2794)
			(end -0.12065 0.2794)
			(stroke
				(width 0.1)
				(type default)
			)
			(layer "F.Fab")
		)
		(fp_line
			(start 0.120396 0.3048)
			(end 0.120396 0.2794)
			(stroke
				(width 0.1)
				(type default)
			)
			(layer "F.Fab")
		)
		(fp_line
			(start 0.12065 -0.3048)
			(end 0.67945 -0.3048)
			(stroke
				(width 0.1)
				(type default)
			)
			(layer "F.Fab")
		)
		(fp_line
			(start 0.12065 -0.2794)
			(end 0.12065 -0.3048)
			(stroke
				(width 0.1)
				(type default)
			)
			(layer "F.Fab")
		)
		(fp_line
			(start 0.67945 -0.3048)
			(end 0.67945 0.3048)
			(stroke
				(width 0.1)
				(type default)
			)
			(layer "F.Fab")
		)
		(fp_line
			(start 0.67945 0.3048)
			(end 0.120396 0.3048)
			(stroke
				(width 0.1)
				(type default)
			)
			(layer "F.Fab")
		)
		(pad "1" smd circle
			(at -0.40005 0)
			(size 0 0)
			(layers "F.Cu" "F.Mask" "F.Paste")
			(net "SMB_SML1_PMBUS_3V3AUX_PCH_SDA")
		)
		(pad "2" smd circle
			(at 0.40005 0)
			(size 0 0)
			(layers "F.Cu" "F.Mask" "F.Paste")
			(net "SMB_PMBUS_SML1_ME_SDA")
		)
	)
)
